(kicad_pcb
	(version 20260206)
	(generator "pcbnew")
	(generator_version "10.0")
	(general
		(thickness 1.6)
		(legacy_teardrops no)
	)
	(paper "A4")
	(title_block
		(title "04192023_DAF0TMB3IC0_F0TG_MB_C_brd_V02_OCP.brd")
		(comment 1 "Grand Teton / footprint 2417 of 8354 (U6015), pads 224-336 of 354")
	)
	(layers
		(0 "F.Cu" signal "TOP")
		(4 "In1.Cu" signal "GND")
		(6 "In2.Cu" signal "IN1")
		(8 "In3.Cu" signal "GND1")
		(10 "In4.Cu" signal "IN2")
		(12 "In5.Cu" signal "GND2")
		(14 "In6.Cu" signal "IN3")
		(16 "In7.Cu" signal "GND3")
		(18 "In8.Cu" signal "VCC")
		(20 "In9.Cu" signal "VCC1")
		(22 "In10.Cu" signal "GND4")
		(24 "In11.Cu" signal "IN4")
		(26 "In12.Cu" signal "GND5")
		(28 "In13.Cu" signal "IN5")
		(30 "In14.Cu" signal "GND6")
		(32 "In15.Cu" signal "IN6")
		(34 "In16.Cu" signal "GND7")
		(2 "B.Cu" signal "BOTTOM")
		(9 "F.Adhes" user "F.Adhesive")
		(11 "B.Adhes" user "B.Adhesive")
		(13 "F.Paste" user "Package Geometry/Pastemask Top")
		(15 "B.Paste" user "Package Geometry/Pastemask Bottom")
		(5 "F.SilkS" user "Ref Des/Silkscreen Top")
		(7 "B.SilkS" user "Ref Des/Silkscreen Bottom")
		(1 "F.Mask" user "Board Geometry/Soldermask Top")
		(3 "B.Mask" user "Board Geometry/Soldermask Bottom")
		(17 "Dwgs.User" user "User.Drawings")
		(19 "Cmts.User" user "User.Comments")
		(21 "Eco1.User" user "User.Eco1")
		(23 "Eco2.User" user "User.Eco2")
		(25 "Edge.Cuts" user "Board Geometry/Outline")
		(27 "Margin" user)
		(31 "F.CrtYd" user "Package Geometry/Place Bound Top")
		(29 "B.CrtYd" user "Package Geometry/Place Bound Bottom")
		(35 "F.Fab" user "Ref Des/Assembly Top")
		(33 "B.Fab" user "Ref Des/Assembly Bottom")
	)
	(footprint ""
		(layer "F.Cu")
		(at 88.995758 -387.342634)
		(property "Reference" "U6015"
			(at -7.723124 -7.528052 0)
			(unlocked yes)
			(layer "F.SilkS")
			(effects
				(font
					(size 0.7874 0.5842)
					(thickness 0.1524)
				)
				(justify left)
			)
		)
		(property "Value" ""
			(at 0 0 0)
			(layer "F.Fab")
			(effects
				(font
					(size 1.27 1.27)
				)
			)
		)
		(duplicate_pad_numbers_are_jumpers no)
		(pad "DY32" smd circle
			(at -5.997448 2.724912)
			(size 0.381 0.381)
			(layers "F.Cu" "F.Mask" "F.Paste")
			(net "GND")
		)
		(pad "E8" smd circle
			(at 10.366502 -1.988312)
			(size 0.3048 0.3048)
			(layers "F.Cu" "F.Mask" "F.Paste")
			(net "JTAG_TRST_RT_CPU1_P1_N")
		)
		(pad "E11" smd circle
			(at 10.366502 -1.388364)
			(size 0.3048 0.3048)
			(layers "F.Cu" "F.Mask" "F.Paste")
			(net "RXDET_BYP_RT_CPU1_P1")
		)
		(pad "E14" smd circle
			(at 10.366502 -0.788416)
			(size 0.3048 0.3048)
			(layers "F.Cu" "F.Mask" "F.Paste")
			(net "GND")
		)
		(pad "E18" smd circle
			(at 10.366502 -0.188468)
			(size 0.3048 0.3048)
			(layers "F.Cu" "F.Mask" "F.Paste")
			(net "Net_2220")
		)
		(pad "E27" smd circle
			(at 10.366502 1.61163)
			(size 0.3048 0.3048)
			(layers "F.Cu" "F.Mask" "F.Paste")
			(net "GND")
		)
		(pad "E30" smd circle
			(at 10.366502 2.211578)
			(size 0.3048 0.3048)
			(layers "F.Cu" "F.Mask" "F.Paste")
			(net "GND")
		)
		(pad "E33" smd circle
			(at 10.366502 2.811526)
			(size 0.3048 0.3048)
			(layers "F.Cu" "F.Mask" "F.Paste")
			(net "GND")
		)
		(pad "EA2" smd circle
			(at -6.050026 -3.41884)
			(size 0.3048 0.3048)
			(layers "F.Cu" "F.Mask" "F.Paste")
			(net "GND")
		)
		(pad "EA34" smd circle
			(at -6.050026 3.420364)
			(size 0.3048 0.3048)
			(layers "F.Cu" "F.Mask" "F.Paste")
			(net "GND")
		)
		(pad "EB1" smd oval
			(at -6.35 -3.938524)
			(size 0.254 0.3302)
			(layers "F.Cu" "F.Mask" "F.Paste")
			(net "GND")
		)
		(pad "EB35" smd oval
			(at -6.35 3.940048)
			(size 0.254 0.3302)
			(layers "F.Cu" "F.Mask" "F.Paste")
			(net "GND")
		)
		(pad "EC7" smd circle
			(at -6.397498 -2.12471)
			(size 0.381 0.381)
			(layers "F.Cu" "F.Mask" "F.Paste")
			(net "P5E_CPU1_P1_TX_BUF_DP<2>")
		)
		(pad "EC26" smd circle
			(at -6.397498 1.339342)
			(size 0.381 0.381)
			(layers "F.Cu" "F.Mask" "F.Paste")
			(net "P5E_CPU1_P1_RX_DP<2>")
		)
		(pad "ED2" smd circle
			(at -6.649974 -3.41884)
			(size 0.3048 0.3048)
			(layers "F.Cu" "F.Mask" "F.Paste")
			(net "P5E_CPU1_P1_RX_BUF_DN<2>")
		)
		(pad "ED34" smd circle
			(at -6.649974 3.420364)
			(size 0.3048 0.3048)
			(layers "F.Cu" "F.Mask" "F.Paste")
			(net "P5E_CPU1_P1_TX_C_DN<2>")
		)
		(pad "EE10" smd circle
			(at -6.797294 -1.431798)
			(size 0.381 0.381)
			(layers "F.Cu" "F.Mask" "F.Paste")
			(net "P5E_CPU1_P1_TX_BUF_DN<2>")
		)
		(pad "EE29" smd circle
			(at -6.797294 2.032254)
			(size 0.381 0.381)
			(layers "F.Cu" "F.Mask" "F.Paste")
			(net "P5E_CPU1_P1_RX_DN<2>")
		)
		(pad "EF1" smd oval
			(at -6.949948 -3.938524)
			(size 0.254 0.3302)
			(layers "F.Cu" "F.Mask" "F.Paste")
			(net "P5E_CPU1_P1_RX_BUF_DP<2>")
		)
		(pad "EF35" smd oval
			(at -6.949948 3.940048)
			(size 0.254 0.3302)
			(layers "F.Cu" "F.Mask" "F.Paste")
			(net "P5E_CPU1_P1_TX_C_DP<2>")
		)
		(pad "EG4" smd circle
			(at -7.197344 -2.817368)
			(size 0.381 0.381)
			(layers "F.Cu" "F.Mask" "F.Paste")
			(net "GND")
		)
		(pad "EG13" smd circle
			(at -7.197344 -0.79629)
			(size 0.3048 0.3048)
			(layers "F.Cu" "F.Mask" "F.Paste")
			(net "GND")
		)
		(pad "EG17" smd circle
			(at -7.197344 -0.296164)
			(size 0.3048 0.3048)
			(layers "F.Cu" "F.Mask" "F.Paste")
			(net "P0V9_CPU1_RT1_2A")
		)
		(pad "EG20" smd circle
			(at -7.197344 0.203708)
			(size 0.3048 0.3048)
			(layers "F.Cu" "F.Mask" "F.Paste")
			(net "P0V9_CPU1_RT1_2A")
		)
		(pad "EG22" smd circle
			(at -7.197344 0.703834)
			(size 0.3048 0.3048)
			(layers "F.Cu" "F.Mask" "F.Paste")
			(net "GND")
		)
		(pad "EG32" smd circle
			(at -7.197344 2.724912)
			(size 0.381 0.381)
			(layers "F.Cu" "F.Mask" "F.Paste")
			(net "GND")
		)
		(pad "EH2" smd circle
			(at -7.249922 -3.41884)
			(size 0.3048 0.3048)
			(layers "F.Cu" "F.Mask" "F.Paste")
			(net "GND")
		)
		(pad "EH34" smd circle
			(at -7.249922 3.420364)
			(size 0.3048 0.3048)
			(layers "F.Cu" "F.Mask" "F.Paste")
			(net "GND")
		)
		(pad "EJ1" smd oval
			(at -7.549896 -3.938524)
			(size 0.254 0.3302)
			(layers "F.Cu" "F.Mask" "F.Paste")
			(net "GND")
		)
		(pad "EJ35" smd oval
			(at -7.549896 3.940048)
			(size 0.254 0.3302)
			(layers "F.Cu" "F.Mask" "F.Paste")
			(net "GND")
		)
		(pad "EK7" smd circle
			(at -7.597394 -2.12471)
			(size 0.381 0.381)
			(layers "F.Cu" "F.Mask" "F.Paste")
			(net "P5E_CPU1_P1_TX_BUF_DP<1>")
		)
		(pad "EK26" smd circle
			(at -7.597394 1.339342)
			(size 0.381 0.381)
			(layers "F.Cu" "F.Mask" "F.Paste")
			(net "P5E_CPU1_P1_RX_DP<1>")
		)
		(pad "EL2" smd circle
			(at -7.850124 -3.41884)
			(size 0.3048 0.3048)
			(layers "F.Cu" "F.Mask" "F.Paste")
			(net "P5E_CPU1_P1_RX_BUF_DN<1>")
		)
		(pad "EL34" smd circle
			(at -7.850124 3.420364)
			(size 0.3048 0.3048)
			(layers "F.Cu" "F.Mask" "F.Paste")
			(net "P5E_CPU1_P1_TX_C_DP<1>")
		)
		(pad "EM10" smd circle
			(at -7.997444 -1.431798)
			(size 0.381 0.381)
			(layers "F.Cu" "F.Mask" "F.Paste")
			(net "P5E_CPU1_P1_TX_BUF_DN<1>")
		)
		(pad "EM29" smd circle
			(at -7.997444 2.032254)
			(size 0.381 0.381)
			(layers "F.Cu" "F.Mask" "F.Paste")
			(net "P5E_CPU1_P1_RX_DN<1>")
		)
		(pad "EN1" smd oval
			(at -8.150098 -3.938524)
			(size 0.254 0.3302)
			(layers "F.Cu" "F.Mask" "F.Paste")
			(net "P5E_CPU1_P1_RX_BUF_DP<1>")
		)
		(pad "EN35" smd oval
			(at -8.150098 3.940048)
			(size 0.254 0.3302)
			(layers "F.Cu" "F.Mask" "F.Paste")
			(net "P5E_CPU1_P1_TX_C_DN<1>")
		)
		(pad "EP4" smd circle
			(at -8.397494 -2.817368)
			(size 0.381 0.381)
			(layers "F.Cu" "F.Mask" "F.Paste")
			(net "GND")
		)
		(pad "EP13" smd circle
			(at -8.397494 -0.79629)
			(size 0.3048 0.3048)
			(layers "F.Cu" "F.Mask" "F.Paste")
			(net "GND")
		)
		(pad "EP17" smd circle
			(at -8.397494 -0.296164)
			(size 0.3048 0.3048)
			(layers "F.Cu" "F.Mask" "F.Paste")
			(net "P0V9_CPU1_RT1_2A")
		)
		(pad "EP20" smd circle
			(at -8.397494 0.203708)
			(size 0.3048 0.3048)
			(layers "F.Cu" "F.Mask" "F.Paste")
			(net "P0V9_CPU1_RT1_2A")
		)
		(pad "EP22" smd circle
			(at -8.397494 0.703834)
			(size 0.3048 0.3048)
			(layers "F.Cu" "F.Mask" "F.Paste")
			(net "GND")
		)
		(pad "EP32" smd circle
			(at -8.397494 2.724912)
			(size 0.381 0.381)
			(layers "F.Cu" "F.Mask" "F.Paste")
			(net "GND")
		)
		(pad "ER2" smd circle
			(at -8.450072 -3.41884)
			(size 0.3048 0.3048)
			(layers "F.Cu" "F.Mask" "F.Paste")
			(net "GND")
		)
		(pad "ER34" smd circle
			(at -8.450072 3.420364)
			(size 0.3048 0.3048)
			(layers "F.Cu" "F.Mask" "F.Paste")
			(net "GND")
		)
		(pad "ET1" smd oval
			(at -8.750046 -3.938524)
			(size 0.254 0.3302)
			(layers "F.Cu" "F.Mask" "F.Paste")
			(net "GND")
		)
		(pad "ET35" smd oval
			(at -8.750046 3.940048)
			(size 0.254 0.3302)
			(layers "F.Cu" "F.Mask" "F.Paste")
			(net "GND")
		)
		(pad "EU7" smd circle
			(at -8.79729 -2.12471)
			(size 0.381 0.381)
			(layers "F.Cu" "F.Mask" "F.Paste")
			(net "P5E_CPU1_P1_TX_BUF_DP<0>")
		)
		(pad "EU26" smd circle
			(at -8.79729 1.339342)
			(size 0.381 0.381)
			(layers "F.Cu" "F.Mask" "F.Paste")
			(net "P5E_CPU1_P1_RX_DP<0>")
		)
		(pad "EV2" smd circle
			(at -9.05002 -3.41884)
			(size 0.3048 0.3048)
			(layers "F.Cu" "F.Mask" "F.Paste")
			(net "P5E_CPU1_P1_RX_BUF_DN<0>")
		)
		(pad "EV34" smd circle
			(at -9.05002 3.420364)
			(size 0.3048 0.3048)
			(layers "F.Cu" "F.Mask" "F.Paste")
			(net "P5E_CPU1_P1_TX_C_DN<0>")
		)
		(pad "EW10" smd circle
			(at -9.19734 -1.431798)
			(size 0.381 0.381)
			(layers "F.Cu" "F.Mask" "F.Paste")
			(net "P5E_CPU1_P1_TX_BUF_DN<0>")
		)
		(pad "EW29" smd circle
			(at -9.19734 2.032254)
			(size 0.381 0.381)
			(layers "F.Cu" "F.Mask" "F.Paste")
			(net "P5E_CPU1_P1_RX_DN<0>")
		)
		(pad "EY1" smd oval
			(at -9.349994 -3.938524)
			(size 0.254 0.3302)
			(layers "F.Cu" "F.Mask" "F.Paste")
			(net "P5E_CPU1_P1_RX_BUF_DP<0>")
		)
		(pad "EY35" smd oval
			(at -9.349994 3.940048)
			(size 0.254 0.3302)
			(layers "F.Cu" "F.Mask" "F.Paste")
			(net "P5E_CPU1_P1_TX_C_DP<0>")
		)
		(pad "F2" smd circle
			(at 10.150094 -3.41884)
			(size 0.3048 0.3048)
			(layers "F.Cu" "F.Mask" "F.Paste")
			(net "RST_RT_CPU1_P1_PERST_N")
		)
		(pad "F34" smd circle
			(at 10.150094 3.420364)
			(size 0.3048 0.3048)
			(layers "F.Cu" "F.Mask" "F.Paste")
			(net "RT_CPU1_P1_ADDR1")
		)
		(pad "FA15" smd circle
			(at -9.59739 -0.738886)
			(size 0.381 0.381)
			(layers "F.Cu" "F.Mask" "F.Paste")
			(net "GND")
		)
		(pad "FA32" smd circle
			(at -9.59739 2.724912)
			(size 0.381 0.381)
			(layers "F.Cu" "F.Mask" "F.Paste")
			(net "GND")
		)
		(pad "FB2" smd circle
			(at -9.649968 -3.41884)
			(size 0.3048 0.3048)
			(layers "F.Cu" "F.Mask" "F.Paste")
			(net "GND")
		)
		(pad "FB34" smd circle
			(at -9.649968 3.420364)
			(size 0.3048 0.3048)
			(layers "F.Cu" "F.Mask" "F.Paste")
			(net "GND")
		)
		(pad "FC3" smd circle
			(at -9.846818 -2.888488)
			(size 0.3048 0.3048)
			(layers "F.Cu" "F.Mask" "F.Paste")
			(net "GND")
		)
		(pad "FC6" smd circle
			(at -9.846818 -2.288286)
			(size 0.3048 0.3048)
			(layers "F.Cu" "F.Mask" "F.Paste")
			(net "GND")
		)
		(pad "FC9" smd circle
			(at -9.846818 -1.688338)
			(size 0.3048 0.3048)
			(layers "F.Cu" "F.Mask" "F.Paste")
			(net "GND")
		)
		(pad "FC19" smd circle
			(at -9.846818 0.111506)
			(size 0.3048 0.3048)
			(layers "F.Cu" "F.Mask" "F.Paste")
			(net "GND")
		)
		(pad "FC23" smd circle
			(at -9.846818 0.711708)
			(size 0.3048 0.3048)
			(layers "F.Cu" "F.Mask" "F.Paste")
			(net "GND")
		)
		(pad "FC25" smd circle
			(at -9.846818 1.311656)
			(size 0.3048 0.3048)
			(layers "F.Cu" "F.Mask" "F.Paste")
			(net "GND")
		)
		(pad "FC28" smd circle
			(at -9.846818 1.911604)
			(size 0.3048 0.3048)
			(layers "F.Cu" "F.Mask" "F.Paste")
			(net "GND")
		)
		(pad "FD1" smd oval
			(at -9.949942 -3.938524)
			(size 0.254 0.3302)
			(layers "F.Cu" "F.Mask" "F.Paste")
			(net "GND")
		)
		(pad "FD35" smd oval
			(at -9.949942 3.940048)
			(size 0.254 0.3302)
			(layers "F.Cu" "F.Mask" "F.Paste")
			(net "GND")
		)
		(pad "FE2" smd circle
			(at -10.249916 -3.41884)
			(size 0.3048 0.3048)
			(layers "F.Cu" "F.Mask" "F.Paste")
			(net "NCF_CPU1_P1_GND")
		)
		(pad "FE34" smd circle
			(at -10.249916 3.420364)
			(size 0.3048 0.3048)
			(layers "F.Cu" "F.Mask" "F.Paste")
			(net "NCF_CPU1_P1_GND")
		)
		(pad "FF5" smd circle
			(at -10.366248 -2.588514)
			(size 0.3048 0.3048)
			(layers "F.Cu" "F.Mask" "F.Paste")
			(net "SMB_RT_CPU1_P1_ROM_MUX_1D_R_SCL")
		)
		(pad "FF8" smd circle
			(at -10.366248 -1.988312)
			(size 0.3048 0.3048)
			(layers "F.Cu" "F.Mask" "F.Paste")
			(net "JTAG_TEST_MODE_RT_CPU1_P1")
		)
		(pad "FF11" smd circle
			(at -10.366248 -1.388364)
			(size 0.3048 0.3048)
			(layers "F.Cu" "F.Mask" "F.Paste")
			(net "RST_RT_CPU1_P1_RESET_N")
		)
		(pad "FF14" smd circle
			(at -10.366248 -0.788416)
			(size 0.3048 0.3048)
			(layers "F.Cu" "F.Mask" "F.Paste")
			(net "GND")
		)
		(pad "FF18" smd circle
			(at -10.366248 -0.188468)
			(size 0.3048 0.3048)
			(layers "F.Cu" "F.Mask" "F.Paste")
			(net "CLK_100M_RETIMER_CPU1_P1_DN")
		)
		(pad "FF21" smd circle
			(at -10.366248 0.41148)
			(size 0.3048 0.3048)
			(layers "F.Cu" "F.Mask" "F.Paste")
			(net "GND")
		)
		(pad "FF24" smd circle
			(at -10.366248 1.011682)
			(size 0.3048 0.3048)
			(layers "F.Cu" "F.Mask" "F.Paste")
			(net "TEST0_RT_CPU1_P1")
		)
		(pad "FF27" smd circle
			(at -10.366248 1.61163)
			(size 0.3048 0.3048)
			(layers "F.Cu" "F.Mask" "F.Paste")
			(net "TEST1_RT_CPU1_P1")
		)
		(pad "FF30" smd circle
			(at -10.366248 2.211578)
			(size 0.3048 0.3048)
			(layers "F.Cu" "F.Mask" "F.Paste")
			(net "TEST2_RT_CPU1_P1")
		)
		(pad "FF33" smd circle
			(at -10.366248 2.811526)
			(size 0.3048 0.3048)
			(layers "F.Cu" "F.Mask" "F.Paste")
			(net "RT_CPU1_P1_SCAN_MODE")
		)
		(pad "FG1" smd oval
			(at -10.54989 -3.938524)
			(size 0.254 0.3302)
			(layers "F.Cu" "F.Mask" "F.Paste")
			(net "NCF_CPU1_P1_GND")
		)
		(pad "FG35" smd oval
			(at -10.54989 3.940048)
			(size 0.254 0.3302)
			(layers "F.Cu" "F.Mask" "F.Paste")
			(net "NCF_CPU1_P1_GND")
		)
		(pad "FH2" smd circle
			(at -10.850118 -3.41884)
			(size 0.3048 0.3048)
			(layers "F.Cu" "F.Mask" "F.Paste")
			(net "NCF_CPU1_P1_GND")
		)
		(pad "FH34" smd circle
			(at -10.850118 3.420364)
			(size 0.3048 0.3048)
			(layers "F.Cu" "F.Mask" "F.Paste")
			(net "NCF_CPU1_P1_GND")
		)
		(pad "FJ3" smd oval
			(at -10.885932 -2.888488 90)
			(size 0.254 0.3302)
			(layers "F.Cu" "F.Mask" "F.Paste")
			(net "SMB_RT_CPU1_P1_ROM_MUX_1D_R_SDA")
		)
		(pad "FJ6" smd oval
			(at -10.885932 -2.288286 90)
			(size 0.254 0.3302)
			(layers "F.Cu" "F.Mask" "F.Paste")
			(net "Net_2218")
		)
		(pad "FJ9" smd oval
			(at -10.885932 -1.688338 90)
			(size 0.254 0.3302)
			(layers "F.Cu" "F.Mask" "F.Paste")
			(net "MODE_RT_CPU1_P1")
		)
		(pad "FJ12" smd oval
			(at -10.885932 -1.08839 90)
			(size 0.254 0.3302)
			(layers "F.Cu" "F.Mask" "F.Paste")
			(net "GND")
		)
		(pad "FJ16" smd oval
			(at -10.885932 -0.488442 90)
			(size 0.254 0.3302)
			(layers "F.Cu" "F.Mask" "F.Paste")
			(net "CLK_100M_RETIMER_CPU1_P1_DP")
		)
		(pad "FJ19" smd oval
			(at -10.885932 0.111506 90)
			(size 0.254 0.3302)
			(layers "F.Cu" "F.Mask" "F.Paste")
			(net "GND")
		)
		(pad "FJ23" smd oval
			(at -10.885932 0.711708 90)
			(size 0.254 0.3302)
			(layers "F.Cu" "F.Mask" "F.Paste")
			(net "Net_2219")
		)
		(pad "FJ25" smd oval
			(at -10.885932 1.311656 90)
			(size 0.254 0.3302)
			(layers "F.Cu" "F.Mask" "F.Paste")
			(net "GPIO2_RT_CPU1_P1")
		)
		(pad "FJ28" smd oval
			(at -10.885932 1.911604 90)
			(size 0.254 0.3302)
			(layers "F.Cu" "F.Mask" "F.Paste")
			(net "GPIO3_RT_CPU1_P1")
		)
		(pad "FJ31" smd oval
			(at -10.885932 2.511552 90)
			(size 0.254 0.3302)
			(layers "F.Cu" "F.Mask" "F.Paste")
			(net "Net_55")
		)
		(pad "G1" smd oval
			(at 9.85012 -3.938524)
			(size 0.254 0.3302)
			(layers "F.Cu" "F.Mask" "F.Paste")
			(net "RT_CPU1_P1_VQPS")
		)
		(pad "G35" smd oval
			(at 9.85012 3.940048)
			(size 0.254 0.3302)
			(layers "F.Cu" "F.Mask" "F.Paste")
			(net "CLKREQ_RT_CPU1_P1_N")
		)
		(pad "H12" smd circle
			(at 9.846818 -1.08839)
			(size 0.3048 0.3048)
			(layers "F.Cu" "F.Mask" "F.Paste")
			(net "GND")
		)
		(pad "H16" smd circle
			(at 9.846818 -0.488442)
			(size 0.3048 0.3048)
			(layers "F.Cu" "F.Mask" "F.Paste")
			(net "GND")
		)
		(pad "H19" smd circle
			(at 9.846818 0.111506)
			(size 0.3048 0.3048)
			(layers "F.Cu" "F.Mask" "F.Paste")
			(net "GND")
		)
		(pad "H31" smd circle
			(at 9.846818 2.511552)
			(size 0.3048 0.3048)
			(layers "F.Cu" "F.Mask" "F.Paste")
			(net "GND")
		)
		(pad "J4" smd circle
			(at 9.602724 -2.817368)
			(size 0.381 0.381)
			(layers "F.Cu" "F.Mask" "F.Paste")
			(net "GND")
		)
		(pad "J22" smd circle
			(at 9.602724 0.703834)
			(size 0.3048 0.3048)
			(layers "F.Cu" "F.Mask" "F.Paste")
			(net "GND")
		)
		(pad "K2" smd circle
			(at 9.549892 -3.41884)
			(size 0.3048 0.3048)
			(layers "F.Cu" "F.Mask" "F.Paste")
			(net "GND")
		)
		(pad "K34" smd circle
			(at 9.549892 3.420364)
			(size 0.3048 0.3048)
			(layers "F.Cu" "F.Mask" "F.Paste")
			(net "GND")
		)
		(pad "L1" smd oval
			(at 9.249918 -3.938524)
			(size 0.254 0.3302)
			(layers "F.Cu" "F.Mask" "F.Paste")
			(net "GND")
		)
		(pad "L35" smd oval
			(at 9.249918 3.940048)
			(size 0.254 0.3302)
			(layers "F.Cu" "F.Mask" "F.Paste")
			(net "GND")
		)
		(pad "M7" smd circle
			(at 9.202674 -2.12471)
			(size 0.381 0.381)
			(layers "F.Cu" "F.Mask" "F.Paste")
			(net "P5E_CPU1_P1_TX_BUF_DP<15>")
		)
		(pad "M26" smd circle
			(at 9.202674 1.339342)
			(size 0.381 0.381)
			(layers "F.Cu" "F.Mask" "F.Paste")
			(net "P5E_CPU1_P1_RX_DP<15>")
		)
		(pad "N2" smd circle
			(at 8.949944 -3.41884)
			(size 0.3048 0.3048)
			(layers "F.Cu" "F.Mask" "F.Paste")
			(net "P5E_CPU1_P1_RX_BUF_DN<15>")
		)
		(pad "N34" smd circle
			(at 8.949944 3.420364)
			(size 0.3048 0.3048)
			(layers "F.Cu" "F.Mask" "F.Paste")
			(net "P5E_CPU1_P1_TX_C_DN<15>")
		)
	)
)
